(kicad_pcb
	(version 20260206)
	(generator "pcbnew")
	(generator_version "10.0")
	(general
		(thickness 1.6)
		(legacy_teardrops no)
	)
	(paper "A4")
	(title_block
		(title "Wiwynn_Tioga_Pass_MB.brd")
		(comment 1 "Tioga Pass / footprints 4496-4502 of 4770")
	)
	(layers
		(0 "F.Cu" signal "TOP")
		(4 "In1.Cu" signal "L2GND")
		(6 "In2.Cu" signal "L3")
		(8 "In3.Cu" signal "L4GND")
		(10 "In4.Cu" signal "L5")
		(12 "In5.Cu" signal "L6GND")
		(14 "In6.Cu" signal "L7VCC")
		(16 "In7.Cu" signal "L8VCC")
		(18 "In8.Cu" signal "L9GND")
		(20 "In9.Cu" signal "L10")
		(22 "In10.Cu" signal "L11GND")
		(24 "In11.Cu" signal "L12")
		(26 "In12.Cu" signal "L13GND")
		(2 "B.Cu" signal "BOTTOM")
		(9 "F.Adhes" user "F.Adhesive")
		(11 "B.Adhes" user "B.Adhesive")
		(13 "F.Paste" user "Package Geometry/Pastemask Top")
		(15 "B.Paste" user "Package Geometry/Pastemask Bottom")
		(5 "F.SilkS" user "Ref Des/Silkscreen Top")
		(7 "B.SilkS" user "Ref Des/Silkscreen Bottom")
		(1 "F.Mask" user "Board Geometry/Soldermask Top")
		(3 "B.Mask" user "Board Geometry/Soldermask Bottom")
		(17 "Dwgs.User" user "User.Drawings")
		(19 "Cmts.User" user "User.Comments")
		(21 "Eco1.User" user "User.Eco1")
		(23 "Eco2.User" user "User.Eco2")
		(25 "Edge.Cuts" user "Board Geometry/Outline")
		(27 "Margin" user)
		(31 "F.CrtYd" user "Package Geometry/Place Bound Top")
		(29 "B.CrtYd" user "Package Geometry/Place Bound Bottom")
		(35 "F.Fab" user "Ref Des/Assembly Top")
		(33 "B.Fab" user "Ref Des/Assembly Bottom")
	)
	(footprint ""
		(layer "B.Cu")
		(at 428.8409 -17.272 -90)
		(property "Reference" "R1U16"
			(at 0 0 90)
			(layer "B.SilkS")
			(hide yes)
			(effects
				(font
					(size 1.27 1.27)
				)
				(justify mirror)
			)
		)
		(property "Value" ""
			(at 0 0 90)
			(layer "B.Fab")
			(effects
				(font
					(size 1.27 1.27)
				)
				(justify mirror)
			)
		)
		(duplicate_pad_numbers_are_jumpers no)
		(fp_poly
			(pts
				(xy 0.2794 -0.1016) (xy -0.2794 -0.1016) (xy -0.2794 0.9906) (xy 0.2794 0.9906)
			)
			(stroke
				(width 0)
				(type default)
			)
			(fill no)
			(layer "B.CrtYd")
		)
		(fp_line
			(start -0.2794 0.9906)
			(end -0.2794 -0.1016)
			(stroke
				(width 0.1)
				(type default)
			)
			(layer "B.Fab")
		)
		(fp_line
			(start 0.2794 0.9906)
			(end -0.2794 0.9906)
			(stroke
				(width 0.1)
				(type default)
			)
			(layer "B.Fab")
		)
		(fp_line
			(start -0.2794 -0.1016)
			(end 0.2794 -0.1016)
			(stroke
				(width 0.1)
				(type default)
			)
			(layer "B.Fab")
		)
		(fp_line
			(start 0.2794 -0.1016)
			(end 0.2794 0.9906)
			(stroke
				(width 0.1)
				(type default)
			)
			(layer "B.Fab")
		)
		(pad "1" smd rect
			(at 0 0 90)
			(size 0.508 0.508)
			(layers "B.Cu" "B.Mask" "B.Paste")
			(net "FM_BOARD_SKU_ID1")
		)
		(pad "2" smd rect
			(at 0 0.889 90)
			(size 0.508 0.508)
			(layers "B.Cu" "B.Mask" "B.Paste")
			(net "GND")
		)
		(zone
			(layer "B.Cu")
			(hatch none 0.5)
			(connect_pads
				(clearance 0)
			)
			(min_thickness 0.25)
			(keepout
				(tracks not_allowed)
				(vias allowed)
				(pads allowed)
				(copperpour not_allowed)
				(footprints allowed)
			)
			(placement
				(enabled no)
				(sheetname "")
			)
			(fill
				(thermal_gap 0.5)
				(thermal_bridge_width 0.5)
				(island_removal_mode 0)
			)
			(polygon
				(pts
					(xy 428.2059 -17.018) (xy 428.2059 -17.526) (xy 428.5869 -17.526) (xy 428.5869 -17.018)
				)
			)
		)
		(zone
			(layer "B.Cu")
			(hatch none 0.5)
			(connect_pads
				(clearance 0)
			)
			(min_thickness 0.25)
			(keepout
				(tracks allowed)
				(vias not_allowed)
				(pads allowed)
				(copperpour not_allowed)
				(footprints allowed)
			)
			(placement
				(enabled no)
				(sheetname "")
			)
			(fill
				(thermal_gap 0.5)
				(thermal_bridge_width 0.5)
				(island_removal_mode 0)
			)
			(polygon
				(pts
					(xy 428.5869 -17.018) (xy 428.5869 -17.526) (xy 428.2059 -17.526) (xy 428.2059 -17.018)
				)
			)
		)
	)
	(footprint ""
		(layer "B.Cu")
		(at 438.404 -52.3875)
		(property "Reference" "C2R16"
			(at 0 0 0)
			(layer "B.SilkS")
			(hide yes)
			(effects
				(font
					(size 1.27 1.27)
				)
				(justify mirror)
			)
		)
		(property "Value" ""
			(at 0 0 0)
			(layer "B.Fab")
			(effects
				(font
					(size 1.27 1.27)
				)
				(justify mirror)
			)
		)
		(duplicate_pad_numbers_are_jumpers no)
		(fp_poly
			(pts
				(xy -0.3048 -0.1016) (xy -0.3048 0.9906) (xy 0.3048 0.9906) (xy 0.3048 -0.1016)
			)
			(stroke
				(width 0)
				(type default)
			)
			(fill no)
			(layer "B.CrtYd")
		)
		(fp_line
			(start -0.3048 -0.1016)
			(end 0.3048 -0.1016)
			(stroke
				(width 0.1)
				(type default)
			)
			(layer "B.Fab")
		)
		(fp_line
			(start -0.3048 0.9906)
			(end -0.3048 -0.1016)
			(stroke
				(width 0.1)
				(type default)
			)
			(layer "B.Fab")
		)
		(fp_line
			(start 0.3048 -0.1016)
			(end 0.3048 0.9906)
			(stroke
				(width 0.1)
				(type default)
			)
			(layer "B.Fab")
		)
		(fp_line
			(start 0.3048 0.9906)
			(end -0.3048 0.9906)
			(stroke
				(width 0.1)
				(type default)
			)
			(layer "B.Fab")
		)
		(pad "1" smd rect
			(at 0 0 180)
			(size 0.508 0.508)
			(layers "B.Cu" "B.Mask" "B.Paste")
			(net "P12V_STBY")
		)
		(pad "2" smd rect
			(at 0 0.889 180)
			(size 0.508 0.508)
			(layers "B.Cu" "B.Mask" "B.Paste")
			(net "GND")
		)
		(zone
			(layer "B.Cu")
			(hatch none 0.5)
			(connect_pads
				(clearance 0)
			)
			(min_thickness 0.25)
			(keepout
				(tracks allowed)
				(vias not_allowed)
				(pads allowed)
				(copperpour not_allowed)
				(footprints allowed)
			)
			(placement
				(enabled no)
				(sheetname "")
			)
			(fill
				(thermal_gap 0.5)
				(thermal_bridge_width 0.5)
				(island_removal_mode 0)
			)
			(polygon
				(pts
					(xy 438.658 -52.1335) (xy 438.15 -52.1335) (xy 438.15 -51.7525) (xy 438.658 -51.7525)
				)
			)
		)
		(zone
			(layer "B.Cu")
			(hatch none 0.5)
			(connect_pads
				(clearance 0)
			)
			(min_thickness 0.25)
			(keepout
				(tracks not_allowed)
				(vias allowed)
				(pads allowed)
				(copperpour not_allowed)
				(footprints allowed)
			)
			(placement
				(enabled no)
				(sheetname "")
			)
			(fill
				(thermal_gap 0.5)
				(thermal_bridge_width 0.5)
				(island_removal_mode 0)
			)
			(polygon
				(pts
					(xy 438.658 -51.7525) (xy 438.15 -51.7525) (xy 438.15 -52.1335) (xy 438.658 -52.1335)
				)
			)
		)
	)
	(footprint ""
		(layer "B.Cu")
		(at 7.2898 -122.936)
		(property "Reference" "EU9M1"
			(at 4.5212 -0.35433 0)
			(unlocked yes)
			(layer "B.SilkS")
			(effects
				(font
					(size 0.7874 0.5842)
					(thickness 0.1524)
				)
				(justify left mirror)
			)
		)
		(property "Value" ""
			(at 0 0 0)
			(layer "B.Fab")
			(effects
				(font
					(size 1.27 1.27)
				)
				(justify mirror)
			)
		)
		(duplicate_pad_numbers_are_jumpers no)
		(fp_circle
			(center 0.702056 -0.595376)
			(end 0.829056 -0.595376)
			(stroke
				(width 0.254)
				(type default)
			)
			(fill no)
			(layer "B.SilkS")
		)
		(fp_rect
			(start -1.4732 1.549908)
			(end -0.5842 -0.050292)
			(stroke
				(width 0)
				(type default)
			)
			(fill yes)
			(layer "B.Paste")
		)
		(fp_rect
			(start -2.078736 1.799844)
			(end 0.021336 -0.300228)
			(stroke
				(width 0)
				(type default)
			)
			(fill no)
			(layer "B.CrtYd")
		)
		(fp_line
			(start -2.078736 -0.300228)
			(end -2.078736 1.799844)
			(stroke
				(width 0.1)
				(type default)
			)
			(layer "B.Fab")
		)
		(fp_line
			(start -2.078736 1.799844)
			(end 0.021336 1.799844)
			(stroke
				(width 0.1)
				(type default)
			)
			(layer "B.Fab")
		)
		(fp_line
			(start 0.021336 -0.300228)
			(end -2.078736 -0.300228)
			(stroke
				(width 0.1)
				(type default)
			)
			(layer "B.Fab")
		)
		(fp_line
			(start 0.021336 1.799844)
			(end 0.021336 -0.300228)
			(stroke
				(width 0.1)
				(type default)
			)
			(layer "B.Fab")
		)
		(fp_circle
			(center 0.702056 -0.595376)
			(end 0.829056 -0.595376)
			(stroke
				(width 0.254)
				(type default)
			)
			(fill no)
			(layer "B.Fab")
		)
		(pad "1" smd rect
			(at 0 0 180)
			(size 0.6604 0.3048)
			(layers "B.Cu" "B.Mask" "B.Paste")
			(net "P5V_STBY")
		)
		(pad "2" smd rect
			(at 0 0.499872 180)
			(size 0.6604 0.3048)
			(layers "B.Cu" "B.Mask" "B.Paste")
			(net "FM_ENABLE_FAN_POWER")
		)
		(pad "3" smd rect
			(at 0 0.999744 180)
			(size 0.6604 0.3048)
			(layers "B.Cu" "B.Mask" "B.Paste")
			(net "P5V_STBY")
		)
		(pad "4" smd rect
			(at 0 1.499616 180)
			(size 0.6604 0.3048)
			(layers "B.Cu" "B.Mask" "B.Paste")
			(net "GND")
		)
		(pad "5" smd rect
			(at -2.0574 1.499616 180)
			(size 0.6604 0.3048)
			(layers "B.Cu" "B.Mask" "B.Paste")
			(net "P12V_STBY")
		)
		(pad "6" smd rect
			(at -2.0574 0.999744 180)
			(size 0.6604 0.3048)
			(layers "B.Cu" "B.Mask" "B.Paste")
			(net "P12V_FAN")
		)
		(pad "7" smd rect
			(at -2.0574 0.499872 180)
			(size 0.6604 0.3048)
			(layers "B.Cu" "B.Mask" "B.Paste")
			(net "P12V_FAN_SWITCH_G")
		)
		(pad "8" smd rect
			(at -2.0574 0 180)
			(size 0.6604 0.3048)
			(layers "B.Cu" "B.Mask" "B.Paste")
			(net "TP_SLG55021_P12V_FAN_8")
		)
		(pad "9" smd rect
			(at -1.0287 0.749808 180)
			(size 0.889 1.6002)
			(layers "B.Cu" "B.Mask" "B.Paste")
			(net "GND")
		)
	)
	(footprint ""
		(layer "B.Cu")
		(at 24.692356 -31.679896 -90)
		(property "Reference" "R9T3"
			(at 0 0 90)
			(layer "B.SilkS")
			(hide yes)
			(effects
				(font
					(size 1.27 1.27)
				)
				(justify mirror)
			)
		)
		(property "Value" ""
			(at 0 0 90)
			(layer "B.Fab")
			(effects
				(font
					(size 1.27 1.27)
				)
				(justify mirror)
			)
		)
		(duplicate_pad_numbers_are_jumpers no)
		(fp_rect
			(start -0.2794 -0.1016)
			(end 0.2794 0.9906)
			(stroke
				(width 0)
				(type default)
			)
			(fill no)
			(layer "B.CrtYd")
		)
		(fp_line
			(start -0.2794 0.9906)
			(end -0.2794 -0.1016)
			(stroke
				(width 0.1)
				(type default)
			)
			(layer "B.Fab")
		)
		(fp_line
			(start 0.2794 0.9906)
			(end -0.2794 0.9906)
			(stroke
				(width 0.1)
				(type default)
			)
			(layer "B.Fab")
		)
		(fp_line
			(start -0.2794 -0.1016)
			(end 0.2794 -0.1016)
			(stroke
				(width 0.1)
				(type default)
			)
			(layer "B.Fab")
		)
		(fp_line
			(start 0.2794 -0.1016)
			(end 0.2794 0.9906)
			(stroke
				(width 0.1)
				(type default)
			)
			(layer "B.Fab")
		)
		(pad "1" smd rect
			(at 0 0 90)
			(size 0.508 0.508)
			(layers "B.Cu" "B.Mask" "B.Paste")
			(net "FM_P12V_HOTSWAP0_EN")
		)
		(pad "2" smd rect
			(at 0 0.889 90)
			(size 0.508 0.508)
			(layers "B.Cu" "B.Mask" "B.Paste")
			(net "GND")
		)
		(zone
			(layer "B.Cu")
			(hatch none 0.5)
			(connect_pads
				(clearance 0)
			)
			(min_thickness 0.25)
			(keepout
				(tracks allowed)
				(vias not_allowed)
				(pads allowed)
				(copperpour not_allowed)
				(footprints allowed)
			)
			(placement
				(enabled no)
				(sheetname "")
			)
			(fill
				(thermal_gap 0.5)
				(thermal_bridge_width 0.5)
				(island_removal_mode 0)
			)
			(polygon
				(pts
					(xy 24.438356 -31.933896) (xy 24.057356 -31.933896) (xy 24.057356 -31.425896) (xy 24.438356 -31.425896)
				)
			)
		)
		(zone
			(layer "B.Cu")
			(hatch none 0.5)
			(connect_pads
				(clearance 0)
			)
			(min_thickness 0.25)
			(keepout
				(tracks not_allowed)
				(vias allowed)
				(pads allowed)
				(copperpour not_allowed)
				(footprints allowed)
			)
			(placement
				(enabled no)
				(sheetname "")
			)
			(fill
				(thermal_gap 0.5)
				(thermal_bridge_width 0.5)
				(island_removal_mode 0)
			)
			(polygon
				(pts
					(xy 24.438356 -31.933896) (xy 24.057356 -31.933896) (xy 24.057356 -31.425896) (xy 24.438356 -31.425896)
				)
			)
		)
	)
	(footprint ""
		(layer "B.Cu")
		(at 108.051854 -85.06714)
		(property "Reference" "C7P2"
			(at 0 0 0)
			(layer "B.SilkS")
			(hide yes)
			(effects
				(font
					(size 1.27 1.27)
				)
				(justify mirror)
			)
		)
		(property "Value" ""
			(at 0 0 0)
			(layer "B.Fab")
			(effects
				(font
					(size 1.27 1.27)
				)
				(justify mirror)
			)
		)
		(duplicate_pad_numbers_are_jumpers no)
		(fp_poly
			(pts
				(xy 0.7239 -0.2159) (xy -0.7239 -0.2159) (xy -0.7239 1.9939) (xy 0.7239 1.9939)
			)
			(stroke
				(width 0)
				(type default)
			)
			(fill no)
			(layer "B.CrtYd")
		)
		(fp_line
			(start -0.7239 -0.2159)
			(end 0.7239 -0.2159)
			(stroke
				(width 0.1)
				(type default)
			)
			(layer "B.Fab")
		)
		(fp_line
			(start -0.7239 1.9939)
			(end -0.7239 -0.2159)
			(stroke
				(width 0.1)
				(type default)
			)
			(layer "B.Fab")
		)
		(fp_line
			(start 0.7239 -0.2159)
			(end 0.7239 1.9939)
			(stroke
				(width 0.1)
				(type default)
			)
			(layer "B.Fab")
		)
		(fp_line
			(start 0.7239 1.9939)
			(end -0.7239 1.9939)
			(stroke
				(width 0.1)
				(type default)
			)
			(layer "B.Fab")
		)
		(pad "1" smd rect
			(at 0 0 180)
			(size 1.27 1.016)
			(layers "B.Cu" "B.Mask" "B.Paste")
			(net "PVDDQ_KLM")
		)
		(pad "2" smd rect
			(at 0 1.778 180)
			(size 1.27 1.016)
			(layers "B.Cu" "B.Mask" "B.Paste")
			(net "GND")
		)
		(zone
			(layer "B.Cu")
			(hatch none 0.5)
			(connect_pads
				(clearance 0)
			)
			(min_thickness 0.25)
			(keepout
				(tracks not_allowed)
				(vias allowed)
				(pads allowed)
				(copperpour not_allowed)
				(footprints allowed)
			)
			(placement
				(enabled no)
				(sheetname "")
			)
			(fill
				(thermal_gap 0.5)
				(thermal_bridge_width 0.5)
				(island_removal_mode 0)
			)
			(polygon
				(pts
					(xy 108.686854 -84.55914) (xy 107.416854 -84.55914) (xy 107.416854 -83.79714) (xy 108.686854 -83.79714)
				)
			)
		)
	)
	(footprint ""
		(layer "B.Cu")
		(at 151.511 -122.809 -90)
		(property "Reference" "C7M6"
			(at -3.10007 3.24612 0)
			(unlocked yes)
			(layer "B.SilkS")
			(effects
				(font
					(size 0.7874 0.5842)
					(thickness 0.1524)
				)
				(justify mirror)
			)
		)
		(property "Value" ""
			(at 0 0 90)
			(layer "B.Fab")
			(effects
				(font
					(size 1.27 1.27)
				)
				(justify mirror)
			)
		)
		(duplicate_pad_numbers_are_jumpers no)
		(fp_line
			(start -2.286 7.366)
			(end -1.600708 7.366)
			(stroke
				(width 0.1524)
				(type default)
			)
			(layer "B.SilkS")
		)
		(fp_line
			(start -2.286 7.366)
			(end -2.286 1.63195)
			(stroke
				(width 0.1524)
				(type default)
			)
			(layer "B.SilkS")
		)
		(fp_line
			(start 2.286 7.366)
			(end 1.60147 7.366)
			(stroke
				(width 0.1524)
				(type default)
			)
			(layer "B.SilkS")
		)
		(fp_line
			(start 2.286 7.366)
			(end 2.286 1.632712)
			(stroke
				(width 0.1524)
				(type default)
			)
			(layer "B.SilkS")
		)
		(fp_line
			(start -2.504948 1.633728)
			(end -1.6002 1.633728)
			(stroke
				(width 0.1524)
				(type default)
			)
			(layer "B.SilkS")
		)
		(fp_line
			(start 2.563114 1.633728)
			(end 1.6002 1.633728)
			(stroke
				(width 0.1524)
				(type default)
			)
			(layer "B.SilkS")
		)
		(fp_line
			(start -2.504948 -1.616456)
			(end -2.504948 1.633728)
			(stroke
				(width 0.1524)
				(type default)
			)
			(layer "B.SilkS")
		)
		(fp_line
			(start -1.6002 -1.616456)
			(end -2.504948 -1.616456)
			(stroke
				(width 0.1524)
				(type default)
			)
			(layer "B.SilkS")
		)
		(fp_line
			(start 1.6002 -1.616456)
			(end 2.563114 -1.616456)
			(stroke
				(width 0.1524)
				(type default)
			)
			(layer "B.SilkS")
		)
		(fp_line
			(start 2.563114 -1.616456)
			(end 2.563114 1.633728)
			(stroke
				(width 0.1524)
				(type default)
			)
			(layer "B.SilkS")
		)
		(fp_rect
			(start 2.286 7.366)
			(end -2.286 -0.254)
			(stroke
				(width 0)
				(type default)
			)
			(fill no)
			(layer "B.CrtYd")
		)
		(fp_line
			(start -2.286 7.366)
			(end 2.286 7.366)
			(stroke
				(width 0.1)
				(type default)
			)
			(layer "B.Fab")
		)
		(fp_line
			(start 2.286 7.366)
			(end 2.286 -0.254)
			(stroke
				(width 0.1)
				(type default)
			)
			(layer "B.Fab")
		)
		(fp_line
			(start -2.286 -0.254)
			(end -2.286 7.366)
			(stroke
				(width 0.1)
				(type default)
			)
			(layer "B.Fab")
		)
		(fp_line
			(start 2.286 -0.254)
			(end -2.286 -0.254)
			(stroke
				(width 0.1)
				(type default)
			)
			(layer "B.Fab")
		)
		(pad "1" smd rect
			(at 0 0 90)
			(size 2.54 3.048)
			(layers "B.Cu" "B.Mask" "B.Paste")
			(net "P12V_STBY")
		)
		(pad "2" smd rect
			(at 0 7.112 90)
			(size 2.54 3.048)
			(layers "B.Cu" "B.Mask" "B.Paste")
			(net "GND")
		)
	)
	(footprint ""
		(layer "B.Cu")
		(at 227.584 -92.583 90)
		(property "Reference" "R5N2"
			(at 0 0 90)
			(layer "B.SilkS")
			(hide yes)
			(effects
				(font
					(size 1.27 1.27)
				)
				(justify mirror)
			)
		)
		(property "Value" ""
			(at 0 0 90)
			(layer "B.Fab")
			(effects
				(font
					(size 1.27 1.27)
				)
				(justify mirror)
			)
		)
		(duplicate_pad_numbers_are_jumpers no)
		(fp_poly
			(pts
				(xy 0.2794 -0.1016) (xy -0.2794 -0.1016) (xy -0.2794 0.9906) (xy 0.2794 0.9906)
			)
			(stroke
				(width 0)
				(type default)
			)
			(fill no)
			(layer "B.CrtYd")
		)
		(fp_line
			(start 0.2794 -0.1016)
			(end 0.2794 0.9906)
			(stroke
				(width 0.1)
				(type default)
			)
			(layer "B.Fab")
		)
		(fp_line
			(start -0.2794 -0.1016)
			(end 0.2794 -0.1016)
			(stroke
				(width 0.1)
				(type default)
			)
			(layer "B.Fab")
		)
		(fp_line
			(start 0.2794 0.9906)
			(end -0.2794 0.9906)
			(stroke
				(width 0.1)
				(type default)
			)
			(layer "B.Fab")
		)
		(fp_line
			(start -0.2794 0.9906)
			(end -0.2794 -0.1016)
			(stroke
				(width 0.1)
				(type default)
			)
			(layer "B.Fab")
		)
		(pad "1" smd rect
			(at 0 0 270)
			(size 0.508 0.508)
			(layers "B.Cu" "B.Mask" "B.Paste")
			(net "P3V3_STBY")
		)
		(pad "2" smd rect
			(at 0 0.889 270)
			(size 0.508 0.508)
			(layers "B.Cu" "B.Mask" "B.Paste")
			(net "FM_CPU0_PROC_ID1")
		)
		(zone
			(layer "B.Cu")
			(hatch none 0.5)
			(connect_pads
				(clearance 0)
			)
			(min_thickness 0.25)
			(keepout
				(tracks allowed)
				(vias not_allowed)
				(pads allowed)
				(copperpour not_allowed)
				(footprints allowed)
			)
			(placement
				(enabled no)
				(sheetname "")
			)
			(fill
				(thermal_gap 0.5)
				(thermal_bridge_width 0.5)
				(island_removal_mode 0)
			)
			(polygon
				(pts
					(xy 227.838 -92.837) (xy 227.838 -92.329) (xy 228.219 -92.329) (xy 228.219 -92.837)
				)
			)
		)
		(zone
			(layer "B.Cu")
			(hatch none 0.5)
			(connect_pads
				(clearance 0)
			)
			(min_thickness 0.25)
			(keepout
				(tracks not_allowed)
				(vias allowed)
				(pads allowed)
				(copperpour not_allowed)
				(footprints allowed)
			)
			(placement
				(enabled no)
				(sheetname "")
			)
			(fill
				(thermal_gap 0.5)
				(thermal_bridge_width 0.5)
				(island_removal_mode 0)
			)
			(polygon
				(pts
					(xy 228.219 -92.837) (xy 228.219 -92.329) (xy 227.838 -92.329) (xy 227.838 -92.837)
				)
			)
		)
	)
)
